(kicad_pcb
	(version 20260206)
	(generator "pcbnew")
	(generator_version "10.0")
	(general
		(thickness 1.6)
		(legacy_teardrops no)
	)
	(paper "A4")
	(title_block
		(title "03242023_DA0F0TMBIJ0_F0T_Motherboard_J_brd_V01_OCP.brd")
		(comment 1 "Grand Teton / footprints 5059-5065 of 6105")
	)
	(layers
		(0 "F.Cu" signal "TOP")
		(4 "In1.Cu" signal "GND")
		(6 "In2.Cu" signal "IN1")
		(8 "In3.Cu" signal "GND1")
		(10 "In4.Cu" signal "IN2")
		(12 "In5.Cu" signal "GND2")
		(14 "In6.Cu" signal "IN3")
		(16 "In7.Cu" signal "GND3")
		(18 "In8.Cu" signal "VCC")
		(20 "In9.Cu" signal "VCC1")
		(22 "In10.Cu" signal "GND4")
		(24 "In11.Cu" signal "IN4")
		(26 "In12.Cu" signal "GND5")
		(28 "In13.Cu" signal "IN5")
		(30 "In14.Cu" signal "GND6")
		(32 "In15.Cu" signal "IN6")
		(34 "In16.Cu" signal "GND7")
		(2 "B.Cu" signal "BOTTOM")
		(9 "F.Adhes" user "F.Adhesive")
		(11 "B.Adhes" user "B.Adhesive")
		(13 "F.Paste" user "Package Geometry/Pastemask Top")
		(15 "B.Paste" user "Package Geometry/Pastemask Bottom")
		(5 "F.SilkS" user "Ref Des/Silkscreen Top")
		(7 "B.SilkS" user "Ref Des/Silkscreen Bottom")
		(1 "F.Mask" user "Board Geometry/Soldermask Top")
		(3 "B.Mask" user "Board Geometry/Soldermask Bottom")
		(17 "Dwgs.User" user "User.Drawings")
		(19 "Cmts.User" user "User.Comments")
		(21 "Eco1.User" user "User.Eco1")
		(23 "Eco2.User" user "User.Eco2")
		(25 "Edge.Cuts" user "Board Geometry/Outline")
		(27 "Margin" user)
		(31 "F.CrtYd" user "Package Geometry/Place Bound Top")
		(29 "B.CrtYd" user "Package Geometry/Place Bound Bottom")
		(35 "F.Fab" user "Ref Des/Assembly Top")
		(33 "B.Fab" user "Ref Des/Assembly Bottom")
	)
	(footprint ""
		(layer "B.Cu")
		(at 90.340688 -341.017606 -90)
		(property "Reference" "PC513_P1_6"
			(at 0 0 90)
			(layer "B.SilkS")
			(hide yes)
			(effects
				(font
					(size 1.27 1.27)
				)
				(justify mirror)
			)
		)
		(property "Value" ""
			(at 0 0 90)
			(layer "B.Fab")
			(effects
				(font
					(size 1.27 1.27)
				)
				(justify mirror)
			)
		)
		(duplicate_pad_numbers_are_jumpers no)
		(fp_line
			(start -1.524 0.762)
			(end 1.524 0.762)
			(stroke
				(width 0.1524)
				(type default)
			)
			(layer "B.SilkS")
		)
		(fp_line
			(start 1.524 0.762)
			(end 1.524 -0.762)
			(stroke
				(width 0.1524)
				(type default)
			)
			(layer "B.SilkS")
		)
		(fp_line
			(start -1.524 -0.762)
			(end -1.524 0.762)
			(stroke
				(width 0.1524)
				(type default)
			)
			(layer "B.SilkS")
		)
		(fp_line
			(start 1.524 -0.762)
			(end -1.524 -0.762)
			(stroke
				(width 0.1524)
				(type default)
			)
			(layer "B.SilkS")
		)
		(fp_line
			(start -1.1049 0.724916)
			(end -1.1049 -0.724916)
			(stroke
				(width 0.1)
				(type default)
			)
			(layer "B.Fab")
		)
		(fp_line
			(start 1.1049 0.724916)
			(end -1.1049 0.724916)
			(stroke
				(width 0.1)
				(type default)
			)
			(layer "B.Fab")
		)
		(fp_line
			(start -1.1049 -0.724916)
			(end 1.1049 -0.724916)
			(stroke
				(width 0.1)
				(type default)
			)
			(layer "B.Fab")
		)
		(fp_line
			(start 1.1049 -0.724916)
			(end 1.1049 0.724916)
			(stroke
				(width 0.1)
				(type default)
			)
			(layer "B.Fab")
		)
		(pad "1" smd rect
			(at 0.889 0 270)
			(size 1.016 1.27)
			(layers "B.Cu" "B.Mask" "B.Paste")
			(net "SW_P12V_PVCCIN_CPU1_FLT")
		)
		(pad "2" smd rect
			(at -0.889 0 270)
			(size 1.016 1.27)
			(layers "B.Cu" "B.Mask" "B.Paste")
			(net "GND")
		)
	)
	(footprint ""
		(layer "B.Cu")
		(at 286.0294 -367.355628 -90)
		(property "Reference" "PR4217"
			(at 0 0 90)
			(layer "B.SilkS")
			(hide yes)
			(effects
				(font
					(size 1.27 1.27)
				)
				(justify mirror)
			)
		)
		(property "Value" ""
			(at 0 0 90)
			(layer "B.Fab")
			(effects
				(font
					(size 1.27 1.27)
				)
				(justify mirror)
			)
		)
		(duplicate_pad_numbers_are_jumpers no)
		(fp_line
			(start -0.7874 0.4064)
			(end 0.7874 0.4064)
			(stroke
				(width 0.1524)
				(type default)
			)
			(layer "B.SilkS")
		)
		(fp_line
			(start 0.7874 0.4064)
			(end 0.7874 -0.4064)
			(stroke
				(width 0.1524)
				(type default)
			)
			(layer "B.SilkS")
		)
		(fp_line
			(start -0.7874 -0.4064)
			(end -0.7874 0.4064)
			(stroke
				(width 0.1524)
				(type default)
			)
			(layer "B.SilkS")
		)
		(fp_line
			(start 0.7874 -0.4064)
			(end -0.7874 -0.4064)
			(stroke
				(width 0.1524)
				(type default)
			)
			(layer "B.SilkS")
		)
		(fp_line
			(start -0.67945 0.3048)
			(end -0.120396 0.3048)
			(stroke
				(width 0.1)
				(type default)
			)
			(layer "B.Fab")
		)
		(fp_line
			(start -0.120396 0.3048)
			(end -0.120396 0.2794)
			(stroke
				(width 0.1)
				(type default)
			)
			(layer "B.Fab")
		)
		(fp_line
			(start 0.12065 0.3048)
			(end 0.67945 0.3048)
			(stroke
				(width 0.1)
				(type default)
			)
			(layer "B.Fab")
		)
		(fp_line
			(start 0.67945 0.3048)
			(end 0.67945 -0.305054)
			(stroke
				(width 0.1)
				(type default)
			)
			(layer "B.Fab")
		)
		(fp_line
			(start -0.120396 0.2794)
			(end 0.12065 0.2794)
			(stroke
				(width 0.1)
				(type default)
			)
			(layer "B.Fab")
		)
		(fp_line
			(start 0.12065 0.2794)
			(end 0.12065 0.3048)
			(stroke
				(width 0.1)
				(type default)
			)
			(layer "B.Fab")
		)
		(fp_line
			(start -0.12065 -0.2794)
			(end -0.12065 -0.3048)
			(stroke
				(width 0.1)
				(type default)
			)
			(layer "B.Fab")
		)
		(fp_line
			(start 0.12065 -0.2794)
			(end -0.12065 -0.2794)
			(stroke
				(width 0.1)
				(type default)
			)
			(layer "B.Fab")
		)
		(fp_line
			(start -0.67945 -0.3048)
			(end -0.67945 0.3048)
			(stroke
				(width 0.1)
				(type default)
			)
			(layer "B.Fab")
		)
		(fp_line
			(start -0.12065 -0.3048)
			(end -0.67945 -0.3048)
			(stroke
				(width 0.1)
				(type default)
			)
			(layer "B.Fab")
		)
		(fp_line
			(start 0.12065 -0.305054)
			(end 0.12065 -0.2794)
			(stroke
				(width 0.1)
				(type default)
			)
			(layer "B.Fab")
		)
		(fp_line
			(start 0.67945 -0.305054)
			(end 0.12065 -0.305054)
			(stroke
				(width 0.1)
				(type default)
			)
			(layer "B.Fab")
		)
		(pad "1" smd circle
			(at 0.40005 0 90)
			(size 0 0)
			(layers "B.Cu" "B.Mask" "B.Paste")
			(net "PVCCFA_EHV_FIVRA_CPU0_IMON4")
		)
		(pad "2" smd circle
			(at -0.40005 0 90)
			(size 0 0)
			(layers "B.Cu" "B.Mask" "B.Paste")
			(net "GND")
		)
	)
	(footprint ""
		(layer "B.Cu")
		(at 419.417246 -362.107226 90)
		(property "Reference" "PC608_P0_1"
			(at 0 0 90)
			(layer "B.SilkS")
			(hide yes)
			(effects
				(font
					(size 1.27 1.27)
				)
				(justify mirror)
			)
		)
		(property "Value" ""
			(at 0 0 90)
			(layer "B.Fab")
			(effects
				(font
					(size 1.27 1.27)
				)
				(justify mirror)
			)
		)
		(duplicate_pad_numbers_are_jumpers no)
		(fp_line
			(start 1.524 -0.762)
			(end -1.524 -0.762)
			(stroke
				(width 0.1524)
				(type default)
			)
			(layer "B.SilkS")
		)
		(fp_line
			(start -1.524 -0.762)
			(end -1.524 0.762)
			(stroke
				(width 0.1524)
				(type default)
			)
			(layer "B.SilkS")
		)
		(fp_line
			(start 1.524 0.762)
			(end 1.524 -0.762)
			(stroke
				(width 0.1524)
				(type default)
			)
			(layer "B.SilkS")
		)
		(fp_line
			(start -1.524 0.762)
			(end 1.524 0.762)
			(stroke
				(width 0.1524)
				(type default)
			)
			(layer "B.SilkS")
		)
		(fp_line
			(start 1.1049 -0.724916)
			(end 1.1049 0.724916)
			(stroke
				(width 0.1)
				(type default)
			)
			(layer "B.Fab")
		)
		(fp_line
			(start -1.1049 -0.724916)
			(end 1.1049 -0.724916)
			(stroke
				(width 0.1)
				(type default)
			)
			(layer "B.Fab")
		)
		(fp_line
			(start 1.1049 0.724916)
			(end -1.1049 0.724916)
			(stroke
				(width 0.1)
				(type default)
			)
			(layer "B.Fab")
		)
		(fp_line
			(start -1.1049 0.724916)
			(end -1.1049 -0.724916)
			(stroke
				(width 0.1)
				(type default)
			)
			(layer "B.Fab")
		)
		(pad "1" smd rect
			(at 0.889 0 90)
			(size 1.016 1.27)
			(layers "B.Cu" "B.Mask" "B.Paste")
			(net "SW_P12V_PVCCFA_EHV_FIVRA_CPU0_R")
		)
		(pad "2" smd rect
			(at -0.889 0 90)
			(size 1.016 1.27)
			(layers "B.Cu" "B.Mask" "B.Paste")
			(net "GND")
		)
	)
	(footprint ""
		(layer "B.Cu")
		(at 55.87492 -344.650314 -90)
		(property "Reference" "PC411_P1_2"
			(at 0 0 90)
			(layer "B.SilkS")
			(hide yes)
			(effects
				(font
					(size 1.27 1.27)
				)
				(justify mirror)
			)
		)
		(property "Value" ""
			(at 0 0 90)
			(layer "B.Fab")
			(effects
				(font
					(size 1.27 1.27)
				)
				(justify mirror)
			)
		)
		(duplicate_pad_numbers_are_jumpers no)
		(fp_line
			(start -1.524 0.762)
			(end 1.524 0.762)
			(stroke
				(width 0.1524)
				(type default)
			)
			(layer "B.SilkS")
		)
		(fp_line
			(start 1.524 0.762)
			(end 1.524 -0.762)
			(stroke
				(width 0.1524)
				(type default)
			)
			(layer "B.SilkS")
		)
		(fp_line
			(start -1.524 -0.762)
			(end -1.524 0.762)
			(stroke
				(width 0.1524)
				(type default)
			)
			(layer "B.SilkS")
		)
		(fp_line
			(start 1.524 -0.762)
			(end -1.524 -0.762)
			(stroke
				(width 0.1524)
				(type default)
			)
			(layer "B.SilkS")
		)
		(fp_line
			(start -1.1049 0.724916)
			(end -1.1049 -0.724916)
			(stroke
				(width 0.1)
				(type default)
			)
			(layer "B.Fab")
		)
		(fp_line
			(start 1.1049 0.724916)
			(end -1.1049 0.724916)
			(stroke
				(width 0.1)
				(type default)
			)
			(layer "B.Fab")
		)
		(fp_line
			(start -1.1049 -0.724916)
			(end 1.1049 -0.724916)
			(stroke
				(width 0.1)
				(type default)
			)
			(layer "B.Fab")
		)
		(fp_line
			(start 1.1049 -0.724916)
			(end 1.1049 0.724916)
			(stroke
				(width 0.1)
				(type default)
			)
			(layer "B.Fab")
		)
		(pad "1" smd rect
			(at 0.889 0 270)
			(size 1.016 1.27)
			(layers "B.Cu" "B.Mask" "B.Paste")
			(net "PVCCFA_EHV_FIVRA_CPU1")
		)
		(pad "2" smd rect
			(at -0.889 0 270)
			(size 1.016 1.27)
			(layers "B.Cu" "B.Mask" "B.Paste")
			(net "GND")
		)
	)
	(footprint ""
		(layer "B.Cu")
		(at 180.155596 -113.77549 180)
		(property "Reference" "C1897"
			(at 0 0 0)
			(layer "B.SilkS")
			(hide yes)
			(effects
				(font
					(size 1.27 1.27)
				)
				(justify mirror)
			)
		)
		(property "Value" ""
			(at 0 0 0)
			(layer "B.Fab")
			(effects
				(font
					(size 1.27 1.27)
				)
				(justify mirror)
			)
		)
		(duplicate_pad_numbers_are_jumpers no)
		(fp_line
			(start 0.69215 0.2921)
			(end 0.69215 -0.2921)
			(stroke
				(width 0.1524)
				(type default)
			)
			(layer "B.SilkS")
		)
		(fp_line
			(start 0.69215 -0.2921)
			(end -0.69215 -0.2921)
			(stroke
				(width 0.1524)
				(type default)
			)
			(layer "B.SilkS")
		)
		(fp_line
			(start -0.69215 0.2921)
			(end 0.69215 0.2921)
			(stroke
				(width 0.1524)
				(type default)
			)
			(layer "B.SilkS")
		)
		(fp_line
			(start -0.69215 -0.2921)
			(end -0.69215 0.2921)
			(stroke
				(width 0.1524)
				(type default)
			)
			(layer "B.SilkS")
		)
		(fp_line
			(start 0.51435 0.2794)
			(end 0.51435 -0.2794)
			(stroke
				(width 0.1)
				(type default)
			)
			(layer "B.Fab")
		)
		(fp_line
			(start 0.51435 -0.2794)
			(end -0.51435 -0.2794)
			(stroke
				(width 0.1)
				(type default)
			)
			(layer "B.Fab")
		)
		(fp_line
			(start -0.51435 0.2794)
			(end 0.51435 0.2794)
			(stroke
				(width 0.1)
				(type default)
			)
			(layer "B.Fab")
		)
		(fp_line
			(start -0.51435 -0.2794)
			(end -0.51435 0.2794)
			(stroke
				(width 0.1)
				(type default)
			)
			(layer "B.Fab")
		)
		(pad "1" smd circle
			(at 0.40005 0)
			(size 0 0)
			(layers "B.Cu" "B.Mask" "B.Paste")
			(net "VCC_PLD_CORE")
		)
		(pad "2" smd circle
			(at -0.40005 0)
			(size 0 0)
			(layers "B.Cu" "B.Mask" "B.Paste")
			(net "GND")
		)
		(zone
			(layer "B.Cu")
			(hatch none 0.5)
			(connect_pads
				(clearance 0)
			)
			(min_thickness 0.25)
			(keepout
				(tracks not_allowed)
				(vias allowed)
				(pads allowed)
				(copperpour not_allowed)
				(footprints allowed)
			)
			(placement
				(enabled no)
				(sheetname "")
			)
			(fill
				(thermal_gap 0.5)
				(thermal_bridge_width 0.5)
				(island_removal_mode 0)
			)
			(polygon
				(pts
					(xy 179.965096 -113.86312) (xy 180.056536 -113.921286) (xy 180.255926 -113.921286) (xy 180.346096 -113.86312)
					(xy 180.346096 -113.68786) (xy 180.255926 -113.62944) (xy 180.056536 -113.62944) (xy 179.965096 -113.687606)
				)
			)
		)
	)
	(footprint ""
		(layer "B.Cu")
		(at 14.407388 -111.004604 90)
		(property "Reference" "C5229"
			(at 0 0 90)
			(layer "B.SilkS")
			(hide yes)
			(effects
				(font
					(size 1.27 1.27)
				)
				(justify mirror)
			)
		)
		(property "Value" ""
			(at 0 0 90)
			(layer "B.Fab")
			(effects
				(font
					(size 1.27 1.27)
				)
				(justify mirror)
			)
		)
		(duplicate_pad_numbers_are_jumpers no)
		(fp_line
			(start 0.7874 -0.4064)
			(end -0.7874 -0.4064)
			(stroke
				(width 0.1524)
				(type default)
			)
			(layer "B.SilkS")
		)
		(fp_line
			(start -0.7874 -0.4064)
			(end -0.7874 0.4064)
			(stroke
				(width 0.1524)
				(type default)
			)
			(layer "B.SilkS")
		)
		(fp_line
			(start 0.7874 0.4064)
			(end 0.7874 -0.4064)
			(stroke
				(width 0.1524)
				(type default)
			)
			(layer "B.SilkS")
		)
		(fp_line
			(start -0.7874 0.4064)
			(end 0.7874 0.4064)
			(stroke
				(width 0.1524)
				(type default)
			)
			(layer "B.SilkS")
		)
		(fp_line
			(start 0.67945 -0.305054)
			(end 0.12065 -0.305054)
			(stroke
				(width 0.1)
				(type default)
			)
			(layer "B.Fab")
		)
		(fp_line
			(start 0.12065 -0.305054)
			(end 0.12065 -0.2794)
			(stroke
				(width 0.1)
				(type default)
			)
			(layer "B.Fab")
		)
		(fp_line
			(start -0.12065 -0.3048)
			(end -0.67945 -0.3048)
			(stroke
				(width 0.1)
				(type default)
			)
			(layer "B.Fab")
		)
		(fp_line
			(start -0.67945 -0.3048)
			(end -0.67945 0.3048)
			(stroke
				(width 0.1)
				(type default)
			)
			(layer "B.Fab")
		)
		(fp_line
			(start 0.12065 -0.2794)
			(end -0.12065 -0.2794)
			(stroke
				(width 0.1)
				(type default)
			)
			(layer "B.Fab")
		)
		(fp_line
			(start -0.12065 -0.2794)
			(end -0.12065 -0.3048)
			(stroke
				(width 0.1)
				(type default)
			)
			(layer "B.Fab")
		)
		(fp_line
			(start 0.12065 0.2794)
			(end 0.12065 0.3048)
			(stroke
				(width 0.1)
				(type default)
			)
			(layer "B.Fab")
		)
		(fp_line
			(start -0.120396 0.2794)
			(end 0.12065 0.2794)
			(stroke
				(width 0.1)
				(type default)
			)
			(layer "B.Fab")
		)
		(fp_line
			(start 0.67945 0.3048)
			(end 0.67945 -0.305054)
			(stroke
				(width 0.1)
				(type default)
			)
			(layer "B.Fab")
		)
		(fp_line
			(start 0.12065 0.3048)
			(end 0.67945 0.3048)
			(stroke
				(width 0.1)
				(type default)
			)
			(layer "B.Fab")
		)
		(fp_line
			(start -0.120396 0.3048)
			(end -0.120396 0.2794)
			(stroke
				(width 0.1)
				(type default)
			)
			(layer "B.Fab")
		)
		(fp_line
			(start -0.67945 0.3048)
			(end -0.120396 0.3048)
			(stroke
				(width 0.1)
				(type default)
			)
			(layer "B.Fab")
		)
		(pad "1" smd circle
			(at 0.40005 0 270)
			(size 0 0)
			(layers "B.Cu" "B.Mask" "B.Paste")
			(net "P3V3_AUX")
		)
		(pad "2" smd circle
			(at -0.40005 0 270)
			(size 0 0)
			(layers "B.Cu" "B.Mask" "B.Paste")
			(net "GND")
		)
	)
	(footprint ""
		(layer "B.Cu")
		(at 328.092816 -26.601674 90)
		(property "Reference" "R1459"
			(at 0 0 90)
			(layer "B.SilkS")
			(hide yes)
			(effects
				(font
					(size 1.27 1.27)
				)
				(justify mirror)
			)
		)
		(property "Value" ""
			(at 0 0 90)
			(layer "B.Fab")
			(effects
				(font
					(size 1.27 1.27)
				)
				(justify mirror)
			)
		)
		(duplicate_pad_numbers_are_jumpers no)
		(fp_line
			(start 0.7874 -0.4064)
			(end -0.7874 -0.4064)
			(stroke
				(width 0.1524)
				(type default)
			)
			(layer "B.SilkS")
		)
		(fp_line
			(start -0.7874 -0.4064)
			(end -0.7874 0.4064)
			(stroke
				(width 0.1524)
				(type default)
			)
			(layer "B.SilkS")
		)
		(fp_line
			(start 0.7874 0.4064)
			(end 0.7874 -0.4064)
			(stroke
				(width 0.1524)
				(type default)
			)
			(layer "B.SilkS")
		)
		(fp_line
			(start -0.7874 0.4064)
			(end 0.7874 0.4064)
			(stroke
				(width 0.1524)
				(type default)
			)
			(layer "B.SilkS")
		)
		(fp_line
			(start 0.67945 -0.305054)
			(end 0.12065 -0.305054)
			(stroke
				(width 0.1)
				(type default)
			)
			(layer "B.Fab")
		)
		(fp_line
			(start 0.12065 -0.305054)
			(end 0.12065 -0.2794)
			(stroke
				(width 0.1)
				(type default)
			)
			(layer "B.Fab")
		)
		(fp_line
			(start -0.12065 -0.3048)
			(end -0.67945 -0.3048)
			(stroke
				(width 0.1)
				(type default)
			)
			(layer "B.Fab")
		)
		(fp_line
			(start -0.67945 -0.3048)
			(end -0.67945 0.3048)
			(stroke
				(width 0.1)
				(type default)
			)
			(layer "B.Fab")
		)
		(fp_line
			(start 0.12065 -0.2794)
			(end -0.12065 -0.2794)
			(stroke
				(width 0.1)
				(type default)
			)
			(layer "B.Fab")
		)
		(fp_line
			(start -0.12065 -0.2794)
			(end -0.12065 -0.3048)
			(stroke
				(width 0.1)
				(type default)
			)
			(layer "B.Fab")
		)
		(fp_line
			(start 0.12065 0.2794)
			(end 0.12065 0.3048)
			(stroke
				(width 0.1)
				(type default)
			)
			(layer "B.Fab")
		)
		(fp_line
			(start -0.120396 0.2794)
			(end 0.12065 0.2794)
			(stroke
				(width 0.1)
				(type default)
			)
			(layer "B.Fab")
		)
		(fp_line
			(start 0.67945 0.3048)
			(end 0.67945 -0.305054)
			(stroke
				(width 0.1)
				(type default)
			)
			(layer "B.Fab")
		)
		(fp_line
			(start 0.12065 0.3048)
			(end 0.67945 0.3048)
			(stroke
				(width 0.1)
				(type default)
			)
			(layer "B.Fab")
		)
		(fp_line
			(start -0.120396 0.3048)
			(end -0.120396 0.2794)
			(stroke
				(width 0.1)
				(type default)
			)
			(layer "B.Fab")
		)
		(fp_line
			(start -0.67945 0.3048)
			(end -0.120396 0.3048)
			(stroke
				(width 0.1)
				(type default)
			)
			(layer "B.Fab")
		)
		(pad "1" smd circle
			(at 0.40005 0 270)
			(size 0 0)
			(layers "B.Cu" "B.Mask" "B.Paste")
			(net "P3V3_AUX")
		)
		(pad "2" smd circle
			(at -0.40005 0 270)
			(size 0 0)
			(layers "B.Cu" "B.Mask" "B.Paste")
			(net "IRQ_PCH_CPU_NMI_EVENT_R_N")
		)
	)
)
